(kicad_pcb
	(version 20211014)
	(generator pcbnew)
	(general
    (thickness 1.6)
  )
	(paper "A4")
	(title_block
    (title "SA800U (Snapdragon 845) Baseboard")
    (date "2023-10-19")
    (rev "1.0.3")
    (company "Antmicro Ltd.")
    (comment 1 "www.antmicro.com")
		(comment 9 "footprints 59-63 of 589")
	)
	(layers
    (0 "F.Cu" signal)
    (1 "In1.Cu" power)
    (2 "In2.Cu" signal)
    (3 "In3.Cu" signal)
    (4 "In4.Cu" power)
    (31 "B.Cu" signal)
    (32 "B.Adhes" user "B.Adhesive")
    (33 "F.Adhes" user "F.Adhesive")
    (34 "B.Paste" user)
    (35 "F.Paste" user)
    (36 "B.SilkS" user "B.Silkscreen")
    (37 "F.SilkS" user "F.Silkscreen")
    (38 "B.Mask" user)
    (39 "F.Mask" user)
    (40 "Dwgs.User" user "User.Drawings")
    (41 "Cmts.User" user "User.Comments")
    (42 "Eco1.User" user "User.Eco1")
    (43 "Eco2.User" user "User.Eco2")
    (44 "Edge.Cuts" user)
    (45 "Margin" user)
    (46 "B.CrtYd" user "B.Courtyard")
    (47 "F.CrtYd" user "F.Courtyard")
    (48 "B.Fab" user)
    (49 "F.Fab" user)
  )
	(footprint "sa800u-baseboard-hw-footprints:LED_0603_1608Metric_G" (layer "F.Cu")
    (tedit 60C2DD7B)
    (at 73.7 129.79 90)
    (descr "LED SMD 0603 Green")
    (tags "LED SMD 0603 Green")
    (property "Author" "Antmicro")
    (property "License" "Apache-2.0")
    (property "MPN" "KP-1608ZGC")
    (property "Manufacturer" "Kingbright")
    (property "Sheetfile" "psu.kicad_sch")
    (property "Sheetname" "PSU")
    (attr smd)
    (fp_text reference "D27" (at -0.82 -0.7 90) (layer "F.SilkS")
      (effects (font (size 0.7 0.7) (thickness 0.15)) (justify left bottom))
    )
    (fp_text value "KP-1608EC" (at 0 1.6 90) (layer "F.Fab")
      (effects (font (size 0.7 0.7) (thickness 0.15)) (justify left bottom))
    )
    (fp_text user "License: Apache-2.0" (at -1.31 5.769 90) (layer "F.Fab") hide
      (effects (font (size 0.7 0.7) (thickness 0.15)) (justify left bottom))
    )
    (fp_text user "${REFERENCE}" (at -1.31 3.769 90) (layer "F.Fab") hide
      (effects (font (size 0.7 0.7) (thickness 0.15)) (justify left bottom))
    )
    (fp_text user "Author: Antmicro" (at -1.31 4.769 90) (layer "F.Fab") hide
      (effects (font (size 0.7 0.7) (thickness 0.15)) (justify left bottom))
    )
    (fp_line (start 1.25 0.32) (end 1.25 -0.32) (layer "F.SilkS") (width 0.15))
    (fp_line (start -0.106328 -0.200008) (end -0.106328 0.199992) (layer "F.SilkS") (width 0.1))
    (fp_line (start -0.106328 -0.000008) (end -0.29 0) (layer "F.SilkS") (width 0.1))
    (fp_line (start -0.27 -0.35) (end 0.27 -0.35) (layer "F.SilkS") (width 0.15))
    (fp_line (start 0.093672 -0.000008) (end -0.106328 0.199992) (layer "F.SilkS") (width 0.1))
    (fp_line (start 0.093672 -0.000008) (end 0.293672 -0.000008) (layer "F.SilkS") (width 0.1))
    (fp_line (start -0.106328 -0.200008) (end 0.093672 -0.000008) (layer "F.SilkS") (width 0.1))
    (fp_line (start 0.093672 -0.200008) (end 0.093672 0.199992) (layer "F.SilkS") (width 0.1))
    (fp_line (start -0.27 0.351) (end 0.27 0.351) (layer "F.SilkS") (width 0.15))
    (fp_rect (start 1.26 0.65) (end -1.26 -0.65) (layer "F.CrtYd") (width 0.05) (fill none))
    (fp_line (start 0.199 -0.2) (end 0.199 -0.1) (layer "F.Fab") (width 0.15))
    (fp_line (start 0.199 0) (end 0.597 0) (layer "F.Fab") (width 0.15))
    (fp_line (start 0.199 0.202) (end 0.199 -0.1) (layer "F.Fab") (width 0.15))
    (fp_line (start -0.201 0) (end -0.201 0.202) (layer "F.Fab") (width 0.15))
    (fp_line (start -0.201 -0.2) (end -0.201 0) (layer "F.Fab") (width 0.15))
    (fp_line (start 0.101 0) (end -0.201 -0.2) (layer "F.Fab") (width 0.15))
    (fp_line (start -0.599 0) (end -0.201 0) (layer "F.Fab") (width 0.15))
    (fp_line (start -0.201 0.202) (end 0.101 0) (layer "F.Fab") (width 0.15))
    (fp_rect (start -0.848 -0.4) (end 0.85 0.402) (layer "F.Fab") (width 0.15) (fill none))
    (pad "1" smd rect (at -0.75 0 270) (size 0.8 0.8) (layers "F.Cu" "F.Paste" "F.Mask")
      (net 378 "Net-(D27-Pad1)") (pinfunction "1") (pintype "passive"))
    (pad "2" smd rect (at 0.75 0 270) (size 0.8 0.8) (layers "F.Cu" "F.Paste" "F.Mask")
      (net 1 "GND") (pinfunction "2") (pintype "passive"))
  )
	(footprint "sa800u-baseboard-hw-footprints:R_0402_1005Metric" (layer "F.Cu")
    (tedit 5FD9C158)
    (at 74.95 130.2 90)
    (descr "Resistor SMD 0402")
    (tags "resistor SMD 0402")
    (property "Author" "Antmicro")
    (property "License" "Apache-2.0")
    (property "MPN" "CR0402-FX-1002GLF")
    (property "Manufacturer" "Bourns")
    (property "Sheetfile" "psu.kicad_sch")
    (property "Sheetname" "PSU")
    (property "Tolerance" "1%")
    (property "Val" "10k")
    (attr smd)
    (fp_text reference "R121" (at -0.97 1.38 90) (layer "F.SilkS")
      (effects (font (size 0.7 0.7) (thickness 0.15)) (justify left bottom))
    )
    (fp_text value "R_10k_0402" (at 0 1.4 90) (layer "F.Fab")
      (effects (font (size 0.7 0.7) (thickness 0.15)) (justify left bottom))
    )
    (fp_text user "License: Apache-2.0" (at -0.95 5.169 90) (layer "F.Fab") hide
      (effects (font (size 0.7 0.7) (thickness 0.15)) (justify left bottom))
    )
    (fp_text user "${REFERENCE}" (at -0.95 3.168 90) (layer "F.Fab") hide
      (effects (font (size 0.7 0.7) (thickness 0.15)) (justify left bottom))
    )
    (fp_text user "Author: Antmicro" (at -0.95 4.169 90) (layer "F.Fab") hide
      (effects (font (size 0.7 0.7) (thickness 0.15)) (justify left bottom))
    )
    (fp_rect (start -0.93 -0.47) (end 0.93 0.47) (layer "F.CrtYd") (width 0.05) (fill none))
    (fp_rect (start -0.5 -0.25) (end 0.5 0.25) (layer "F.Fab") (width 0.15) (fill none))
    (pad "1" smd roundrect (at -0.485 0 90) (size 0.59 0.64) (layers "F.Cu" "F.Paste" "F.Mask") (roundrect_rratio 0.25)
      (net 378 "Net-(D27-Pad1)") (pintype "passive"))
    (pad "2" smd roundrect (at 0.485 0 90) (size 0.59 0.64) (layers "F.Cu" "F.Paste" "F.Mask") (roundrect_rratio 0.25)
      (net 74 "VDD") (pintype "passive"))
  )
	(footprint "sa800u-baseboard-hw-footprints:LED_0603_1608Metric_G" (layer "F.Cu")
    (tedit 60C2DD7B)
    (at 147.45 94.4)
    (descr "LED SMD 0603 Green")
    (tags "LED SMD 0603 Green")
    (property "Author" "Antmicro")
    (property "License" "Apache-2.0")
    (property "MPN" "KP-1608ZGC")
    (property "Manufacturer" "Kingbright")
    (property "Sheetfile" "m2.kicad_sch")
    (property "Sheetname" "M2")
    (attr smd)
    (fp_text reference "D21" (at -1.18 1.28) (layer "F.SilkS")
      (effects (font (size 0.7 0.7) (thickness 0.15)) (justify left bottom))
    )
    (fp_text value "KP-1608EC" (at 0 1.6) (layer "F.Fab")
      (effects (font (size 0.7 0.7) (thickness 0.15)) (justify left bottom))
    )
    (fp_text user "License: Apache-2.0" (at -1.31 5.769) (layer "F.Fab") hide
      (effects (font (size 0.7 0.7) (thickness 0.15)) (justify left bottom))
    )
    (fp_text user "Author: Antmicro" (at -1.31 4.769) (layer "F.Fab") hide
      (effects (font (size 0.7 0.7) (thickness 0.15)) (justify left bottom))
    )
    (fp_text user "${REFERENCE}" (at -1.31 3.769) (layer "F.Fab") hide
      (effects (font (size 0.7 0.7) (thickness 0.15)) (justify left bottom))
    )
    (fp_line (start -0.27 -0.35) (end 0.27 -0.35) (layer "F.SilkS") (width 0.15))
    (fp_line (start -0.106328 -0.200008) (end 0.093672 -0.000008) (layer "F.SilkS") (width 0.1))
    (fp_line (start -0.106328 -0.000008) (end -0.29 0) (layer "F.SilkS") (width 0.1))
    (fp_line (start 0.093672 -0.000008) (end 0.293672 -0.000008) (layer "F.SilkS") (width 0.1))
    (fp_line (start 0.093672 -0.200008) (end 0.093672 0.199992) (layer "F.SilkS") (width 0.1))
    (fp_line (start 1.25 0.32) (end 1.25 -0.32) (layer "F.SilkS") (width 0.15))
    (fp_line (start -0.27 0.351) (end 0.27 0.351) (layer "F.SilkS") (width 0.15))
    (fp_line (start 0.093672 -0.000008) (end -0.106328 0.199992) (layer "F.SilkS") (width 0.1))
    (fp_line (start -0.106328 -0.200008) (end -0.106328 0.199992) (layer "F.SilkS") (width 0.1))
    (fp_rect (start 1.26 0.65) (end -1.26 -0.65) (layer "F.CrtYd") (width 0.05) (fill none))
    (fp_line (start 0.199 -0.2) (end 0.199 -0.1) (layer "F.Fab") (width 0.15))
    (fp_line (start 0.199 0.202) (end 0.199 -0.1) (layer "F.Fab") (width 0.15))
    (fp_line (start -0.201 -0.2) (end -0.201 0) (layer "F.Fab") (width 0.15))
    (fp_line (start -0.201 0.202) (end 0.101 0) (layer "F.Fab") (width 0.15))
    (fp_line (start -0.599 0) (end -0.201 0) (layer "F.Fab") (width 0.15))
    (fp_line (start 0.199 0) (end 0.597 0) (layer "F.Fab") (width 0.15))
    (fp_line (start 0.101 0) (end -0.201 -0.2) (layer "F.Fab") (width 0.15))
    (fp_line (start -0.201 0) (end -0.201 0.202) (layer "F.Fab") (width 0.15))
    (fp_rect (start -0.848 -0.4) (end 0.85 0.402) (layer "F.Fab") (width 0.15) (fill none))
    (pad "1" smd rect (at -0.75 0 180) (size 0.8 0.8) (layers "F.Cu" "F.Paste" "F.Mask")
      (net 373 "Net-(D21-Pad1)") (pinfunction "1") (pintype "passive"))
    (pad "2" smd rect (at 0.75 0 180) (size 0.8 0.8) (layers "F.Cu" "F.Paste" "F.Mask")
      (net 374 "Net-(D21-Pad2)") (pinfunction "2") (pintype "passive"))
  )
	(footprint "sa800u-baseboard-hw-footprints:R_0402_1005Metric" (layer "F.Cu")
    (tedit 5FD9C158)
    (at 96.5 120.68 -90)
    (descr "Resistor SMD 0402")
    (tags "resistor SMD 0402")
    (property "Author" "Antmicro")
    (property "License" "Apache-2.0")
    (property "MPN" "CR0402-FX-4702GLF")
    (property "Manufacturer" "Bourns")
    (property "Sheetfile" "som.kicad_sch")
    (property "Sheetname" "SoM")
    (property "Tolerance" "1%")
    (property "Val" "47k")
    (attr smd)
    (fp_text reference "R70" (at 3.03 -0.38 -90) (layer "F.SilkS")
      (effects (font (size 0.7 0.7) (thickness 0.15)) (justify left bottom))
    )
    (fp_text value "R_47k_0402" (at 0 1.4 -90) (layer "F.Fab")
      (effects (font (size 0.7 0.7) (thickness 0.15)) (justify left bottom))
    )
    (fp_text user "Author: Antmicro" (at -0.95 4.169 -90) (layer "F.Fab") hide
      (effects (font (size 0.7 0.7) (thickness 0.15)) (justify left bottom))
    )
    (fp_text user "${REFERENCE}" (at -0.95 3.168 -90) (layer "F.Fab") hide
      (effects (font (size 0.7 0.7) (thickness 0.15)) (justify left bottom))
    )
    (fp_text user "License: Apache-2.0" (at -0.95 5.169 -90) (layer "F.Fab") hide
      (effects (font (size 0.7 0.7) (thickness 0.15)) (justify left bottom))
    )
    (fp_rect (start -0.93 -0.47) (end 0.93 0.47) (layer "F.CrtYd") (width 0.05) (fill none))
    (fp_rect (start -0.5 -0.25) (end 0.5 0.25) (layer "F.Fab") (width 0.15) (fill none))
    (pad "1" smd roundrect (at -0.485 0 270) (size 0.59 0.64) (layers "F.Cu" "F.Paste" "F.Mask") (roundrect_rratio 0.25)
      (net 398 "Net-(R70-Pad1)") (pintype "passive"))
    (pad "2" smd roundrect (at 0.485 0 270) (size 0.59 0.64) (layers "F.Cu" "F.Paste" "F.Mask") (roundrect_rratio 0.25)
      (net 1 "GND") (pintype "passive"))
  )
	(footprint "sa800u-baseboard-hw-footprints:USB-C_12401610E4_2A" locked (layer "F.Cu")
    (tedit 6215EC4A)
    (at 87.75 147.95)
    (property "Author" "Antmicro")
    (property "License" "Apache-2.0")
    (property "MPN" "12401598E4#2A")
    (property "Manufacturer" "Amphenol")
    (property "Sheetfile" "usb-pd.kicad_sch")
    (property "Sheetname" "USB-PD")
    (attr smd)
    (fp_text reference "J11" (at 4.25 -5.55) (layer "F.SilkS")
      (effects (font (size 0.7 0.7) (thickness 0.15)) (justify left bottom))
    )
    (fp_text value "12401598E4_2A" (at 0 6.549) (layer "F.Fab")
      (effects (font (size 0.7 0.7) (thickness 0.15)) (justify left bottom))
    )
    (fp_text user "License: Apache-2.0" (at -4.901 10.948) (layer "F.Fab") hide
      (effects (font (size 0.7 0.7) (thickness 0.15)) (justify left bottom))
    )
    (fp_text user "${REFERENCE}" (at -4.901 8.55) (layer "F.Fab") hide
      (effects (font (size 0.7 0.7) (thickness 0.15)) (justify left bottom))
    )
    (fp_text user "Author: Antmicro" (at -4.901 9.749) (layer "F.Fab") hide
      (effects (font (size 0.7 0.7) (thickness 0.15)) (justify left bottom))
    )
    (fp_line (start -4.601 5.448) (end -4.1 5.448) (layer "F.SilkS") (width 0.15))
    (fp_line (start -4.601 -5.25) (end -4.601 -4.75) (layer "F.SilkS") (width 0.15))
    (fp_line (start 4.599 -5.25) (end 4.099 -5.25) (layer "F.SilkS") (width 0.15))
    (fp_line (start 4.599 5.448) (end 4.099 5.448) (layer "F.SilkS") (width 0.15))
    (fp_line (start -4.601 5.448) (end -4.601 4.948) (layer "F.SilkS") (width 0.15))
    (fp_line (start 4.599 -5.25) (end 4.599 -4.75) (layer "F.SilkS") (width 0.15))
    (fp_line (start -4.601 -5.25) (end -4.1 -5.25) (layer "F.SilkS") (width 0.15))
    (fp_line (start 4.599 5.448) (end 4.599 4.948) (layer "F.SilkS") (width 0.15))
    (fp_circle (center -3.101 -5.25) (end -3.052 -5.25) (layer "F.SilkS") (width 0.15) (fill solid))
    (fp_rect (start -4.92 -5.46) (end 4.9 5.44) (layer "F.CrtYd") (width 0.05) (fill none))
    (fp_line (start -4.491 -5.162) (end 4.49 -5.162) (layer "F.Fab") (width 0.15))
    (fp_line (start 4.49 -5.162) (end 4.49 5.339) (layer "F.Fab") (width 0.15))
    (fp_line (start -4.491 5.339) (end 4.49 5.339) (layer "F.Fab") (width 0.15))
    (fp_line (start -4.491 -5.162) (end -4.491 5.339) (layer "F.Fab") (width 0.15))
    (pad "" np_thru_hole circle locked (at -3.601 -4.25) (size 0.65 0.65) (drill 0.65) (layers *.Cu *.Mask))
    (pad "" np_thru_hole oval locked (at 3.6 -4.25) (size 0.95 0.65) (drill oval 0.95 0.65) (layers *.Cu *.Mask))
    (pad "A1" smd rect locked (at -2.75 -4.912) (size 0.3 0.7) (layers "F.Cu" "F.Paste" "F.Mask")
      (net 1 "GND") (pintype "passive"))
    (pad "A2" smd rect locked (at -2.25 -4.912) (size 0.3 0.7) (layers "F.Cu" "F.Paste" "F.Mask")
      (net 465 "unconnected-(J11-PadA2)") (pintype "passive+no_connect"))
    (pad "A3" smd rect locked (at -1.75 -4.912) (size 0.3 0.7) (layers "F.Cu" "F.Paste" "F.Mask")
      (net 464 "unconnected-(J11-PadA3)") (pintype "passive+no_connect"))
    (pad "A4" smd rect locked (at -1.25 -4.912) (size 0.3 0.7) (layers "F.Cu" "F.Paste" "F.Mask")
      (net 107 "/USB-PD/PD_VBUS") (pintype "passive"))
    (pad "A5" smd rect locked (at -0.75 -4.912) (size 0.3 0.7) (layers "F.Cu" "F.Paste" "F.Mask")
      (net 143 "/USB-PD/PD_CC1") (pintype "passive"))
    (pad "A6" smd rect locked (at -0.25 -4.912) (size 0.3 0.7) (layers "F.Cu" "F.Paste" "F.Mask")
      (net 463 "unconnected-(J11-PadA6)") (pintype "passive+no_connect"))
    (pad "A7" smd rect locked (at 0.247 -4.912) (size 0.3 0.7) (layers "F.Cu" "F.Paste" "F.Mask")
      (net 462 "unconnected-(J11-PadA7)") (pintype "passive+no_connect"))
    (pad "A8" smd rect locked (at 0.747 -4.912) (size 0.3 0.7) (layers "F.Cu" "F.Paste" "F.Mask")
      (net 461 "unconnected-(J11-PadA8)") (pintype "passive+no_connect"))
    (pad "A9" smd rect locked (at 1.249 -4.912) (size 0.3 0.7) (layers "F.Cu" "F.Paste" "F.Mask")
      (net 107 "/USB-PD/PD_VBUS") (pintype "passive"))
    (pad "A10" smd rect locked (at 1.749 -4.912) (size 0.3 0.7) (layers "F.Cu" "F.Paste" "F.Mask")
      (net 460 "unconnected-(J11-PadA10)") (pintype "passive+no_connect"))
    (pad "A11" smd rect locked (at 2.249 -4.912) (size 0.3 0.7) (layers "F.Cu" "F.Paste" "F.Mask")
      (net 459 "unconnected-(J11-PadA11)") (pintype "passive+no_connect"))
    (pad "A12" smd rect locked (at 2.749 -4.912) (size 0.3 0.7) (layers "F.Cu" "F.Paste" "F.Mask")
      (net 1 "GND") (pintype "passive"))
    (pad "B1" smd rect locked (at 2.499 -3.21) (size 0.3 0.7) (layers "F.Cu" "F.Paste" "F.Mask")
      (net 1 "GND") (pintype "passive"))
    (pad "B2" smd rect locked (at 1.999 -3.21) (size 0.3 0.7) (layers "F.Cu" "F.Paste" "F.Mask")
      (net 458 "unconnected-(J11-PadB2)") (pintype "passive+no_connect"))
    (pad "B3" smd rect locked (at 1.499 -3.21) (size 0.3 0.7) (layers "F.Cu" "F.Paste" "F.Mask")
      (net 457 "unconnected-(J11-PadB3)") (pintype "passive+no_connect"))
    (pad "B4" smd rect locked (at 0.997 -3.21) (size 0.3 0.7) (layers "F.Cu" "F.Paste" "F.Mask")
      (net 107 "/USB-PD/PD_VBUS") (pintype "passive"))
    (pad "B5" smd rect locked (at 0.497 -3.21) (size 0.3 0.7) (layers "F.Cu" "F.Paste" "F.Mask")
      (net 144 "/USB-PD/PD_CC2") (pintype "passive"))
    (pad "B6" smd rect locked (at 0 -3.21) (size 0.3 0.7) (layers "F.Cu" "F.Paste" "F.Mask")
      (net 456 "unconnected-(J11-PadB6)") (pintype "passive+no_connect"))
    (pad "B7" smd rect locked (at -0.5 -3.21) (size 0.3 0.7) (layers "F.Cu" "F.Paste" "F.Mask")
      (net 455 "unconnected-(J11-PadB7)") (pintype "passive+no_connect"))
    (pad "B8" smd rect locked (at -1 -3.21) (size 0.3 0.7) (layers "F.Cu" "F.Paste" "F.Mask")
      (net 454 "unconnected-(J11-PadB8)") (pintype "passive+no_connect"))
    (pad "B9" smd rect locked (at -1.5 -3.21) (size 0.3 0.7) (layers "F.Cu" "F.Paste" "F.Mask")
      (net 107 "/USB-PD/PD_VBUS") (pintype "passive"))
    (pad "B10" smd rect locked (at -2 -3.21) (size 0.3 0.7) (layers "F.Cu" "F.Paste" "F.Mask")
      (net 453 "unconnected-(J11-PadB10)") (pintype "passive+no_connect"))
    (pad "B11" smd rect locked (at -2.5 -3.21) (size 0.3 0.7) (layers "F.Cu" "F.Paste" "F.Mask")
      (net 452 "unconnected-(J11-PadB11)") (pintype "passive+no_connect"))
    (pad "B12" smd rect locked (at -3 -3.21) (size 0.3 0.7) (layers "F.Cu" "F.Paste" "F.Mask")
      (net 1 "GND") (pintype "passive"))
    (pad "SH" thru_hole oval locked (at -4.491 2.95) (size 0.85 1.45) (drill oval 0.5 1.1) (layers *.Cu *.Mask)
      (net 1 "GND") (pintype "input"))
    (pad "SH" thru_hole oval locked (at -4.13 -3.001) (size 0.85 1.45) (drill oval 0.5 1.1) (layers *.Cu *.Mask)
      (net 1 "GND") (pintype "input"))
    (pad "SH" thru_hole oval locked (at 4.49 2.95) (size 0.85 1.45) (drill oval 0.5 1.1) (layers *.Cu *.Mask)
      (net 1 "GND") (pintype "input"))
    (pad "SH" thru_hole oval locked (at 4.128 -3.001) (size 0.85 1.45) (drill oval 0.5 1.1) (layers *.Cu *.Mask)
      (net 1 "GND") (pintype "input"))
  )
)
